FILE_TYPE = CONNECTIVITY;
{Allegro Design Entry HDL 16.6-p007 (v16-6-112F) 10/10/2012}
"PAGE_NUMBER" = 236;
0"NC";
1"GND\g";
2"GND\g";
3"GND\g";
4"P5V_STBY\g";
5"GND\g";
6"GND\g";
7"GND\g";
8"GND\g";
9"GND\g";
10"GND\g";
11"GND\g";
12"GND\g";
13"GND\g";
14"GND\g";
15"GND\g";
16"GND\g";
17"GND\g";
18"GND\g";
19"GND\g";
20"P5V_STBY\g";
21"GND\g";
22"GND\g";
23"P1V05_PCH_STBY\g";
24"P1V05_PCH_STBY\g";
25"GND\g";
26"PVNN_PCH_STBY\g";
27"GND\g";
28"GND\g";
29"PVNN_PCH_STBY\g";
30"VR_FET_SW_P12V_STBY_PVDDQ_DEF\g";
31"VR_FET_SW_P12V_STBY_PVDDQ_DEF\g";
32"VR_FET_SW_P12V_STBY_PVDDQ_DEF\g";
33"VR_P1V05_PCH_STBY_PH1_PHASE";
34"VR_PVNN_PCH_PWM1";
35"VR_P1V05_PCH_STBY_PWM1";
36"VR_P1V05_PCH_STBY_PH1_BOOT_R";
37"VR_PVNN_PCH_PH1_PHASE";
38"VR_PVNN_PCH_PH1_BOOT_R";
39"VR_PVNN_PCH_STBY_OCSET";
40"A_TSENSE_PVNN_PCH_TMON";
41"TP_P1V05_PCH_GL_0";
42"A_TSENSE_P1V05_PCH_STBY_TMON";
43"VR_P1V05_PCH_STBY_OCSET";
44"VR_PVNN_PCH_AIREF1";
45"VR_P1V05_PCH_STBY_PH1_PHASE_SW";
46"VR_PVNN_PCH_PH1_PHASE_SW";
47"VR_P1V05_PCH_STBY_PH1_VCIN";
48"VR_PVNN_PCH_PH1_VCIN";
49"VSENSE_PVNN_PCH_STBY_AVSP";
50"VSENSE_PVNN_PCH_STBY_AVSN";
51"VSENSE_PVNN_PCH_STBY_QAT";
52"VR_PVNN_PCH_PH1_PHASE_SW_RC";
53"ISENSE_P1V05_PCH_STBY_PH1_IMON";
54"VR_P1V05_PCH_STBY_PH1_SW_RC";
55"VR_P1V05_PCH_BIREF1";
56"VSENSE_PVNN_PCH_STBY_FPK";
57"TP_PVNN_PCH_GL_0";
58"TP_PVNN_PCH_GL_1";
59"VR_PVNN_PCH_PH1_BOOT";
60"ISENSE_PVNN_PCH_PH1_IMON";
61"VR_P1V05_PCH_STBY_PH1_BOOT";
62"VSENSE_P1V05_PCH_STBY_AVSP";
63"VSENSE_P1V05_PCH_STBY_AVSN";
64"TP_P1V05_PCH_GL_1";
65"GND\g";
%"GND"
"1","(10450,3600)","0","mstr_symbols","I11";
;
SIZE"1B"
CDS_LIB"mstr_symbols"
VOLTAGE"0.0V"
BOM_COST"PROC_VRD_PVCCIO_CPU0"
ROOM"PVCCIO_CPU0"
BODY_TYPE"PLUMBING"
HDL_POWER"GND";
"A\NAC"1;
%"IR354XX"
"1","(9850,4275)","0","mstr_discrete","I116";
;
CDS_SEC"1"
LOCATION"EU7A3"
MATERIAL"IC"
NO_XNET_CONNECTION"1"
PART_NUMBER"H73684-001"
CDS_LIB"mstr_discrete"
CDS_LOCATION"EU7A3"
PACK_TYPE"SM"
SEC_TYPE"SM"
SEC"1"
VALUE"IR35412";
"TOUT_FLT"
$PN"36"40;
"NC"
$PN"31"0;
"OCSET"
$PN"37"39;
"IOUT"
$PN"38"60;
"SW"
$PN"10"46;
"BOOST"
$PN"33"38;
"REFIN"
$PN"39"44;
"PWM"
$PN"34"34;
"PHASE"
$PN"32"37;
"VIN<0>"
$PN"25"30;
"VCC"
$PN"3"48;
"VIN<1>"
$PN"30"30;
"EN"
$PN"35"4;
"VDRV"
$PN"4"4;
"VOS"
$PN"1"26;
"LGND"
$PN"2"1;
"PGND<1>"
$PN"7"1;
"PGND<2>"
$PN"40"1;
"PGND<0>"
$PN"5"1;
"GL<0>"
$PN"6"57;
"GL<1>"
$PN"41"58;
%"IR354XX"
"1","(9875,2525)","0","mstr_discrete","I117";
;
CDS_SEC"1"
NO_XNET_CONNECTION"1"
MATERIAL"IC"
LOCATION"EU7A2"
PART_NUMBER"H73684-001"
CDS_LOCATION"EU7A2"
SEC"1"
SEC_TYPE"SM"
PACK_TYPE"SM"
CDS_LIB"mstr_discrete"
VALUE"IR35412";
"TOUT_FLT"
$PN"36"42;
"NC"
$PN"31"0;
"OCSET"
$PN"37"43;
"IOUT"
$PN"38"53;
"SW"
$PN"10"45;
"BOOST"
$PN"33"36;
"REFIN"
$PN"39"55;
"PWM"
$PN"34"35;
"PHASE"
$PN"32"33;
"VIN<0>"
$PN"25"31;
"VCC"
$PN"3"47;
"VIN<1>"
$PN"30"31;
"EN"
$PN"35"20;
"VDRV"
$PN"4"20;
"VOS"
$PN"1"23;
"LGND"
$PN"2"21;
"PGND<1>"
$PN"7"21;
"PGND<2>"
$PN"40"21;
"PGND<0>"
$PN"5"21;
"GL<0>"
$PN"6"41;
"GL<1>"
$PN"41"64;
%"RES"
"2","(12125,4450)","0","mstr_discrete","I118";
;
CDS_SEC"1"
CDS_LOCATION"R3L15"
WATTAGE"1/16W"
MATERIAL"EMPTY"
LOCATION"R3L15"
VALUE"68.1K"
TOLERANCE"1%"
PACK_TYPE"0402"
PART_NUMBER"G21796-187"
CDS_LIB"mstr_discrete"
SEC"1"
SEC_TYPE"0402";
"A"
$PN"1"39;
"B"
$PN"2"2;
%"GND"
"1","(12125,4200)","0","mstr_symbols","I119";
;
BOM_COST"PROC_VRD_VCCIN_CPU0"
ROOM"PVSA_CPU1_PWR_VR"
VOLTAGE"0"
CDS_LIB"mstr_symbols"
SIZE"1B"
BODY_TYPE"PLUMBING"
HDL_POWER"GND";
"A\NAC"2;
%"RES"
"2","(12150,2700)","0","mstr_discrete","I120";
;
CDS_SEC"1"
CDS_LOCATION"R3L14"
TOLERANCE"1%"
LOCATION"R3L14"
VALUE"68.1K"
WATTAGE"1/16W"
MATERIAL"EMPTY"
PART_NUMBER"G21796-187"
PACK_TYPE"0402"
CDS_LIB"mstr_discrete"
SEC"1"
SEC_TYPE"0402";
"A"
$PN"1"43;
"B"
$PN"2"3;
%"GND"
"1","(12150,2450)","0","mstr_symbols","I121";
;
BOM_COST"PROC_VRD_VCCIN_CPU0"
ROOM"PVSA_CPU1_PWR_VR"
VOLTAGE"0"
CDS_LIB"mstr_symbols"
SIZE"1B"
BODY_TYPE"PLUMBING"
HDL_POWER"GND";
"A\NAC"3;
%"P5V_STBY"
"1","(8525,5150)","0","mstr_symbols","I122";
;
VOLTAGE"5.0V"
SIZE"1B"
CDS_LIB"mstr_symbols"
BODY_TYPE"PLUMBING"
HDL_POWER"P5V_STBY";
"G\NAC"4;
%"CAP_A"
"1","(9125,2025)","0","dev_discrete","I124";
;
CDS_SEC"1"
$SEC"1"
CDS_LOCATION"CT67"
PACK_TYPE"0402V"
VOLTAGE"16V"
LOCATION"CT67"
POP"NOPOP"
TOLERANCE"10%"
MATERIAL"X7R"
PART_NUMBER"A36096-030"
VALUE"0.1UF"
ROOM"PVCCIN_CPU0_PWR_VR"
CDS_LIB"dev_discrete";
"B"
$PN"2"5;
"A"
$PN"1"55;
%"GND"
"1","(9125,1775)","0","mstr_symbols","I125";
;
ROOM"PVCCIN_CPU0_PWR_VR"
BOM_COST"PROC_VRD_VCCIN_CPU0"
SIZE"1B"
VOLTAGE"0"
CDS_LIB"mstr_symbols"
BODY_TYPE"PLUMBING"
HDL_POWER"GND";
"A\NAC"5;
%"GND"
"1","(9125,3500)","0","mstr_symbols","I126";
;
VOLTAGE"0"
SIZE"1B"
BOM_COST"PROC_VRD_VCCIN_CPU0"
ROOM"PVCCIN_CPU0_PWR_VR"
CDS_LIB"mstr_symbols"
BODY_TYPE"PLUMBING"
HDL_POWER"GND";
"A\NAC"6;
%"CAP_A"
"1","(9125,3775)","0","dev_discrete","I127";
;
CDS_SEC"1"
CDS_LOCATION"CT66"
VALUE"0.1UF"
VOLTAGE"16V"
POP"NOPOP"
PACK_TYPE"0402V"
PART_NUMBER"A36096-030"
MATERIAL"X7R"
TOLERANCE"10%"
LOCATION"CT66"
ROOM"PVCCIN_CPU0_PWR_VR"
CDS_LIB"dev_discrete"
SEC"1"
SEC_TYPE"0402V";
"B"
$PN"2"6;
"A"
$PN"1"44;
%"GND"
"1","(10925,4100)","0","mstr_symbols","I130";
;
HDL_POWER"GND"
BODY_TYPE"PLUMBING"
ROOM"VDDQ_KLM_PWR_VR"
VOLTAGE"0"
SIZE"1B"
CDS_LIB"mstr_symbols";
"A\NAC"7;
%"GND"
"1","(10550,3375)","0","mstr_symbols","I133";
;
HDL_POWER"GND"
BODY_TYPE"PLUMBING"
ROOM"PVCCIN_CPU0_PWR_VR"
BOM_COST"PROC_VRD_VCCIN_CPU0"
VOLTAGE"0"
SIZE"1B"
CDS_LIB"mstr_symbols";
"A\NAC"65;
%"CAP"
"1","(10900,2600)","0","mstr_discrete","I134";
;
CDS_SEC"1"
CDS_LOCATION"CT69"
LOCATION"CT69"
PACK_TYPE"0402LF"
PART_NUMBER"A36096-046"
MATERIAL"X7R"
TOLERANCE"10%"
VOLTAGE"50V"
VALUE"1000PF"
POP"NOPOP"
ROOM"VDDQ_KLM_PWR_VR"
CDS_LIB"mstr_discrete"
SEC"1"
SEC_TYPE"0402LF";
"A"
$PN"1"42;
"B"
$PN"2"8;
%"GND"
"1","(10900,2425)","0","mstr_symbols","I135";
;
ROOM"VDDQ_KLM_PWR_VR"
VOLTAGE"0"
SIZE"1B"
CDS_LIB"mstr_symbols"
BODY_TYPE"PLUMBING"
HDL_POWER"GND";
"A\NAC"8;
%"CAP"
"1","(10925,4300)","0","mstr_discrete","I136";
;
CDS_SEC"1"
CDS_LOCATION"CT64"
PART_NUMBER"A36096-046"
POP"NOPOP"
VALUE"1000PF"
VOLTAGE"50V"
TOLERANCE"10%"
MATERIAL"X7R"
PACK_TYPE"0402LF"
LOCATION"CT64"
CDS_LIB"mstr_discrete"
ROOM"VDDQ_KLM_PWR_VR"
SEC"1"
SEC_TYPE"0402LF";
"A"
$PN"1"40;
"B"
$PN"2"7;
%"GND"
"1","(11050,1650)","0","mstr_symbols","I139";
;
HDL_POWER"GND"
BODY_TYPE"PLUMBING"
ROOM"PVCCIN_CPU0_PWR_VR"
BOM_COST"PROC_VRD_VCCIN_CPU0"
VOLTAGE"0"
SIZE"1B"
CDS_LIB"mstr_symbols";
"A\NAC"9;
%"CAP"
"1","(10550,3850)","0","mstr_discrete","I149";
;
CDS_SEC"1"
CDS_LOCATION"CT65"
POP"NOPOP"
TOLERANCE"10%"
LOCATION"CT65"
VOLTAGE"50V"
VALUE"1000PF"
MATERIAL"X7R"
PACK_TYPE"0402LF"
PART_NUMBER"A36096-046"
ROOM"VDDQ_KLM_PWR_VR"
CDS_LIB"mstr_discrete"
SEC_TYPE"0402LF"
SEC"1";
"A"
$PN"1"46;
"B"
$PN"2"52;
%"CAP"
"1","(11050,2150)","0","mstr_discrete","I150";
;
CDS_SEC"1"
CDS_LOCATION"CT68"
PART_NUMBER"A36096-046"
TOLERANCE"10%"
PACK_TYPE"0402LF"
LOCATION"CT68"
VALUE"1000PF"
VOLTAGE"50V"
MATERIAL"X7R"
POP"NOPOP"
CDS_LIB"mstr_discrete"
ROOM"VDDQ_KLM_PWR_VR"
SEC"1"
SEC_TYPE"0402LF";
"A"
$PN"1"45;
"B"
$PN"2"54;
%"RES"
"1","(8025,4050)","0","mstr_discrete","I153";
;
CDS_SEC"1"
CDS_LOCATION"RT44"
LOCATION"RT44"
VALUE"0"
WATTAGE"1/10W"
PART_NUMBER"G22178-002"
PACK_TYPE"0603"
TOLERANCE"5.0%"
MATERIAL"CHIP"
CDS_LIB"mstr_discrete"
BOM_COST"NT_GBE_BASE"
ROOM"NIC_SPRV"
SEC"1"
SEC_TYPE"0603";
"B"
$PN"2"38;
"A"
$PN"1"59;
%"RES"
"1","(8050,2325)","0","mstr_discrete","I154";
;
CDS_SEC"1"
CDS_LOCATION"RT46"
LOCATION"RT46"
VALUE"0"
PACK_TYPE"0603"
WATTAGE"1/10W"
MATERIAL"CHIP"
TOLERANCE"5.0%"
PART_NUMBER"G22178-002"
BOM_COST"NT_GBE_BASE"
ROOM"NIC_SPRV"
CDS_LIB"mstr_discrete"
SEC"1"
SEC_TYPE"0603";
"B"
$PN"2"36;
"A"
$PN"1"61;
%"SC22U16V5MX-4-GP"
"1","(11150,975)","0","w_hdl","I159";
;
CDS_SEC"1"
CDS_LOCATION"C22W23"
LOCATION"C22W23"
VALUE"SC22U16V5MX-4-GP"
ATTRIBUTE"22UF"
TOLERANCE"20%"
PACK_SIZE"0805"
TYPE"X6S"
RATED"16V"
CDS_LMAN_SYM_OUTLINE"-50,25,50,-25"
CDS_LIB"w_hdl"
PART_NUMBER"078.22611.0811"
SEC_TYPE"SMD-BCG5"
SEC"1"
PACK_TYPE"SMD-BCG5";
"2"
$PN"2"15;
"1"
$PN"1"32;
%"CAP"
"1","(8125,4575)","0","mstr_discrete","I16";
;
CDS_SEC"1"
PART_NUMBER"A36096-155"
PACK_TYPE"0402"
TOLERANCE"10%"
MATERIAL"X7R"
VALUE"0.22UF"
VOLTAGE"16V"
LOCATION"C7A8"
CDS_LIB"mstr_discrete"
SEC_TYPE"0402"
SEC"1"
CDS_LOCATION"C7A8"
ROOM"PVNN_PCH_STBY";
"A"
$PN"1"4;
"B"
$PN"2"18;
%"SC22U16V5MX-4-GP"
"1","(11450,975)","0","w_hdl","I160";
;
CDS_SEC"1"
CDS_LOCATION"C22W24"
LOCATION"C22W24"
VALUE"SC22U16V5MX-4-GP"
ATTRIBUTE"22UF"
TOLERANCE"20%"
PACK_SIZE"0805"
TYPE"X6S"
RATED"16V"
CDS_LMAN_SYM_OUTLINE"-50,25,50,-25"
CDS_LIB"w_hdl"
PART_NUMBER"078.22611.0811"
SEC_TYPE"SMD-BCG5"
SEC"1"
PACK_TYPE"SMD-BCG5";
"2"
$PN"2"14;
"1"
$PN"1"32;
%"SC22U16V5MX-4-GP"
"1","(11800,975)","0","w_hdl","I161";
;
CDS_SEC"1"
CDS_LOCATION"C7A13"
LOCATION"C7A13"
VALUE"SC22U16V5MX-4-GP"
PACK_SIZE"0805"
TYPE"X6S"
RATED"16V"
TOLERANCE"20%"
ATTRIBUTE"22UF"
PACK_TYPE"SMD-BCG5"
SEC"1"
SEC_TYPE"SMD-BCG5"
PART_NUMBER"078.22611.0811"
CDS_LIB"w_hdl"
CDS_LMAN_SYM_OUTLINE"-50,25,50,-25";
"2"
$PN"2"13;
"1"
$PN"1"32;
%"SC22U16V5MX-4-GP"
"1","(12100,975)","0","w_hdl","I162";
;
CDS_SEC"1"
CDS_LOCATION"C22W25"
LOCATION"C22W25"
ATTRIBUTE"22UF"
VALUE"SC22U16V5MX-4-GP"
TOLERANCE"20%"
TYPE"X6S"
PACK_SIZE"0805"
RATED"16V"
CDS_LMAN_SYM_OUTLINE"-50,25,50,-25"
CDS_LIB"w_hdl"
PART_NUMBER"078.22611.0811"
SEC_TYPE"SMD-BCG5"
SEC"1"
PACK_TYPE"SMD-BCG5";
"2"
$PN"2"12;
"1"
$PN"1"32;
%"SC22U16V5MX-4-GP"
"1","(12700,975)","0","w_hdl","I163";
;
CDS_SEC"1"
CDS_LOCATION"C22W27"
VALUE"SC22U16V5MX-4-GP"
ATTRIBUTE"22UF"
LOCATION"C22W27"
RATED"16V"
TYPE"X6S"
TOLERANCE"20%"
PACK_SIZE"0805"
PACK_TYPE"SMD-BCG5"
SEC"1"
SEC_TYPE"SMD-BCG5"
PART_NUMBER"078.22611.0811"
CDS_LIB"w_hdl"
CDS_LMAN_SYM_OUTLINE"-50,25,50,-25";
"2"
$PN"2"10;
"1"
$PN"1"32;
%"GND"
"1","(12700,725)","0","mstr_symbols","I164";
;
CDS_LIB"mstr_symbols"
BOM_COST"PVPP_KLM_VR"
ROOM"PVPP_KLM_VR"
BODY_TYPE"PLUMBING"
VOLTAGE"0"
SIZE"1B"
HDL_POWER"GND";
"A\NAC"10;
%"SC22U16V5MX-4-GP"
"1","(12400,975)","0","w_hdl","I165";
;
CDS_SEC"1"
CDS_LOCATION"C22W26"
ATTRIBUTE"22UF"
TYPE"X6S"
PACK_SIZE"0805"
RATED"16V"
TOLERANCE"20%"
LOCATION"C22W26"
VALUE"SC22U16V5MX-4-GP"
CDS_LMAN_SYM_OUTLINE"-50,25,50,-25"
CDS_LIB"w_hdl"
PART_NUMBER"078.22611.0811"
SEC_TYPE"SMD-BCG5"
SEC"1"
PACK_TYPE"SMD-BCG5";
"2"
$PN"2"11;
"1"
$PN"1"32;
%"GND"
"1","(12400,725)","0","mstr_symbols","I166";
;
CDS_LIB"mstr_symbols"
BOM_COST"PVPP_KLM_VR"
ROOM"PVPP_KLM_VR"
BODY_TYPE"PLUMBING"
VOLTAGE"0"
SIZE"1B"
HDL_POWER"GND";
"A\NAC"11;
%"GND"
"1","(12100,725)","0","mstr_symbols","I167";
;
CDS_LIB"mstr_symbols"
BOM_COST"PVPP_KLM_VR"
ROOM"PVPP_KLM_VR"
BODY_TYPE"PLUMBING"
VOLTAGE"0"
SIZE"1B"
HDL_POWER"GND";
"A\NAC"12;
%"GND"
"1","(11800,725)","0","mstr_symbols","I168";
;
CDS_LIB"mstr_symbols"
BOM_COST"PVPP_KLM_VR"
ROOM"PVPP_KLM_VR"
BODY_TYPE"PLUMBING"
VOLTAGE"0"
SIZE"1B"
HDL_POWER"GND";
"A\NAC"13;
%"GND"
"1","(11450,725)","0","mstr_symbols","I169";
;
HDL_POWER"GND"
SIZE"1B"
VOLTAGE"0"
BODY_TYPE"PLUMBING"
ROOM"PVPP_KLM_VR"
BOM_COST"PVPP_KLM_VR"
CDS_LIB"mstr_symbols";
"A\NAC"14;
%"GND"
"1","(11150,725)","0","mstr_symbols","I170";
;
CDS_LIB"mstr_symbols"
BOM_COST"PVPP_KLM_VR"
ROOM"PVPP_KLM_VR"
BODY_TYPE"PLUMBING"
VOLTAGE"0"
SIZE"1B"
HDL_POWER"GND";
"A\NAC"15;
%"SC22U16V5MX-4-GP"
"1","(10850,975)","0","w_hdl","I171";
;
CDS_SEC"1"
CDS_LOCATION"C22W22"
VALUE"SC22U16V5MX-4-GP"
LOCATION"C22W22"
ATTRIBUTE"22UF"
TOLERANCE"20%"
RATED"16V"
TYPE"X6S"
PACK_SIZE"0805"
CDS_LMAN_SYM_OUTLINE"-50,25,50,-25"
CDS_LIB"w_hdl"
PART_NUMBER"078.22611.0811"
SEC_TYPE"SMD-BCG5"
SEC"1"
PACK_TYPE"SMD-BCG5";
"2"
$PN"2"16;
"1"
$PN"1"32;
%"SC22U16V5MX-4-GP"
"1","(10550,975)","0","w_hdl","I172";
;
CDS_SEC"1"
CDS_LOCATION"C7A14"
LOCATION"C7A14"
ATTRIBUTE"22UF"
TOLERANCE"20%"
VALUE"SC22U16V5MX-4-GP"
RATED"16V"
TYPE"X6S"
PACK_SIZE"0805"
CDS_LMAN_SYM_OUTLINE"-50,25,50,-25"
CDS_LIB"w_hdl"
PART_NUMBER"078.22611.0811"
SEC_TYPE"SMD-BCG5"
SEC"1"
PACK_TYPE"SMD-BCG5";
"2"
$PN"2"17;
"1"
$PN"1"32;
%"GND"
"1","(10850,725)","0","mstr_symbols","I173";
;
CDS_LIB"mstr_symbols"
BOM_COST"PVPP_KLM_VR"
ROOM"PVPP_KLM_VR"
BODY_TYPE"PLUMBING"
VOLTAGE"0"
SIZE"1B"
HDL_POWER"GND";
"A\NAC"16;
%"GND"
"1","(10550,725)","0","mstr_symbols","I174";
;
CDS_LIB"mstr_symbols"
BOM_COST"PVPP_KLM_VR"
ROOM"PVPP_KLM_VR"
BODY_TYPE"PLUMBING"
VOLTAGE"0"
SIZE"1B"
HDL_POWER"GND";
"A\NAC"17;
%"RES"
"1","(7425,5050)","0","mstr_discrete","I175";
;
MATERIAL"CHIP"
PACK_TYPE"0402"
PART_NUMBER"G21497-005"
WATTAGE"1/16W"
VALUE"0.0"
LOCATION"R3L1"
TOLERANCE"5%"
CDS_LOCATION"R3L1"
CDS_SEC"1"
ROOM"CPU0"
SEC"1"
SEC_TYPE"0402"
CDS_LIB"mstr_discrete"
BOM_COST"PROC_SIDEBAND";
"B"
$PN"2"4;
"A"
$PN"1"48;
%"RES"
"1","(7325,3300)","0","mstr_discrete","I177";
;
WATTAGE"1/16W"
MATERIAL"CHIP"
LOCATION"R3L4"
VALUE"0.0"
PART_NUMBER"G21497-005"
TOLERANCE"5%"
PACK_TYPE"0402"
CDS_LOCATION"R3L4"
CDS_SEC"1"
ROOM"CPU0"
SEC"1"
SEC_TYPE"0402"
CDS_LIB"mstr_discrete"
BOM_COST"PROC_SIDEBAND";
"B"
$PN"2"20;
"A"
$PN"1"47;
%"IND-300NH-20-GP"
"1","(11375,4000)","1","w_hdl","I178";
;
CDS_SEC"1"
CDS_LOCATION"L7A2"
VALUE"IND-300NH-20-GP"
LOCATION"L7A2"
ATTRIBUTE"300NH"
RATED"ISAT=33A@25C"
PACK_SIZE"DCR=0.17MOHM"
TYPE"IRMS=66A@DELTA_T<40C"
PACK_TYPE"DISCRET-GB1"
SEC"1"
SEC_TYPE"DISCRET-GB1"
CDS_LMAN_SYM_OUTLINE"-75,100,75,-100"
CDS_LIB"w_hdl"
PART_NUMBER"068.3012N.M001";
"F"
$PN"2"26;
"S"
$PN"1"46;
%"IND-300NH-20-GP"
"1","(11400,2300)","1","w_hdl","I179";
;
CDS_SEC"1"
CDS_LOCATION"L7A4"
LOCATION"L7A4"
VALUE"IND-300NH-20-GP"
ATTRIBUTE"300NH"
RATED"ISAT=33A@25C"
PACK_SIZE"DCR=0.17MOHM"
TYPE"IRMS=66A@DELTA_T<40C"
PACK_TYPE"DISCRET-GB1"
SEC"1"
SEC_TYPE"DISCRET-GB1"
CDS_LMAN_SYM_OUTLINE"-75,100,75,-100"
CDS_LIB"w_hdl"
PART_NUMBER"068.3012N.M001";
"F"
$PN"2"23;
"S"
$PN"1"45;
%"SC1U10V2KX-4-GP"
"1","(7800,4525)","0","w_hdl","I180";
;
CDS_SEC"1"
CDS_LOCATION"C3L1"
PACK_SIZE"0402"
RATED"10V"
TOLERANCE"10%"
ATTRIBUTE"1UF"
VALUE"SC1U10V2KX-4-GP"
LOCATION"C3L1"
CDS_LMAN_SYM_OUTLINE"-50,25,50,-25"
CDS_LIB"w_hdl"
PART_NUMBER"78.10523.8FL"
SEC_TYPE"SMD-BCG6"
SEC"1"
PACK_TYPE"SMD-BCG6";
"2"
$PN"2"18;
"1"
$PN"1"4;
%"SC1U10V2KX-4-GP"
"1","(7625,2775)","0","w_hdl","I181";
;
CDS_SEC"1"
CDS_LOCATION"C3L29"
VALUE"SC1U10V2KX-4-GP"
LOCATION"C3L29"
ATTRIBUTE"1UF"
TOLERANCE"10%"
RATED"10V"
PACK_SIZE"0402"
CDS_LMAN_SYM_OUTLINE"-50,25,50,-25"
CDS_LIB"w_hdl"
PART_NUMBER"78.10523.8FL"
SEC_TYPE"SMD-BCG6"
SEC"1"
PACK_TYPE"SMD-BCG6";
"2"
$PN"2"19;
"1"
$PN"1"20;
%"1R3F-GP"
"1","(10550,3550)","0","w_hdl","I182";
;
CDS_SEC"1"
CDS_LOCATION"RT43"
PACK_SIZE"0603"
RATED"1/10W"
LOCATION"RT43"
VALUE"1R3F-GP"
ATTRIBUTE"1 OHM"
TOLERANCE"1%"
POP"NOPOP"
CDS_LMAN_SYM_OUTLINE"-50,75,50,-75"
CDS_LIB"w_hdl"
PART_NUMBER"64.1R005.55L"
SEC_TYPE"RCL_GP"
SEC"1"
PACK_TYPE"RCL_GP";
"2"
$PN"2"65;
"1"
$PN"1"52;
%"1R3F-GP"
"1","(11050,1850)","0","w_hdl","I183";
;
CDS_SEC"1"
CDS_LOCATION"RT45"
PACK_SIZE"0603"
LOCATION"RT45"
RATED"1/10W"
ATTRIBUTE"1 OHM"
TOLERANCE"1%"
POP"NOPOP"
VALUE"1R3F-GP"
PACK_TYPE"RCL_GP"
SEC"1"
SEC_TYPE"RCL_GP"
PART_NUMBER"64.1R005.55L"
CDS_LIB"w_hdl"
CDS_LMAN_SYM_OUTLINE"-50,75,50,-75";
"2"
$PN"2"9;
"1"
$PN"1"54;
%"CAP"
"1","(7300,4500)","0","mstr_discrete","I19";
;
CDS_SEC"1"
MATERIAL"X6S"
TOLERANCE"10%"
VOLTAGE"16V"
PART_NUMBER"D97712-011"
LOCATION"C7A6"
PACK_TYPE"0402"
VALUE"1.0UF"
CDS_LIB"mstr_discrete"
CDS_LOCATION"C7A6"
SEC_TYPE"0402"
SEC"1"
ROOM"P1V05_PCH_STBY_VR";
"A"
$PN"1"48;
"B"
$PN"2"18;
%"CAP_A"
"1","(7025,4550)","0","dev_discrete","I20";
;
CDS_LOCATION"C7A39"
TOLERANCE"10%"
VOLTAGE"16V"
MATERIAL"X7R"
PACK_TYPE"0402V"
PART_NUMBER"A36096-030"
VALUE"0.1UF"
LOCATION"C7A39"
ROOM"PVNN_PCH_STBY"
CDS_SEC"1"
SEC_TYPE"0402V"
SEC"1"
CDS_LIB"dev_discrete";
"B"
$PN"2"18;
"A"
$PN"1"30;
%"CAP"
"1","(6975,3850)","2","mstr_discrete","I21";
;
CDS_SEC"1"
CDS_LOCATION"C7A43"
PACK_TYPE"0402"
VOLTAGE"16V"
TOLERANCE"10%"
PART_NUMBER"A36096-104"
LOCATION"C7A43"
VALUE"0.220UF"
MATERIAL"X7R"
ROOM"PVNN_PCH_STBY"
SEC"1"
SEC_TYPE"0402"
SPOF"TRUE"
CDS_LIB"mstr_discrete";
"A"
$PN"1"59;
"B"
$PN"2"37;
%"CAP"
"1","(6775,4500)","0","mstr_discrete","I22";
;
CDS_SEC"1"
VOLTAGE"16V"
MATERIAL"X6S"
LOCATION"C7A7"
PART_NUMBER"D97712-011"
VALUE"1.0UF"
PACK_TYPE"0402"
TOLERANCE"10%"
CDS_LIB"mstr_discrete"
CDS_LOCATION"C7A7"
ROOM"PVNN_PCH_STBY"
SEC"1"
SEC_TYPE"0402";
"A"
$PN"1"30;
"B"
$PN"2"18;
%"CAP"
"1","(6525,4550)","0","mstr_discrete","I23";
;
CDS_SEC"1"
LOCATION"C3L12"
VALUE"10UF"
PACK_TYPE"0805"
TOLERANCE"10%"
VOLTAGE"16V"
MATERIAL"X6S"
PART_NUMBER"C95333-007"
CDS_LIB"mstr_discrete"
ROOM"PVNN_PCH_STBY"
CDS_LOCATION"C3L12"
SEC"1"
SEC_TYPE"0805";
"A"
$PN"1"30;
"B"
$PN"2"18;
%"CAP"
"1","(6275,4500)","0","mstr_discrete","I24";
;
CDS_SEC"1"
TOLERANCE"10%"
VALUE"10UF"
PACK_TYPE"0805"
VOLTAGE"16V"
MATERIAL"X6S"
LOCATION"C3L11"
PART_NUMBER"C95333-007"
CDS_LIB"mstr_discrete"
CDS_LOCATION"C3L11"
ROOM"PVNN_PCH_STBY"
SEC"1"
SEC_TYPE"0805";
"A"
$PN"1"30;
"B"
$PN"2"18;
%"CAP"
"1","(6000,4550)","0","mstr_discrete","I26";
;
CDS_SEC"1"
TOLERANCE"10%"
VALUE"10UF"
VOLTAGE"16V"
MATERIAL"X6S"
PACK_TYPE"0805"
PART_NUMBER"C95333-007"
LOCATION"C3L8"
ROOM"PVNN_PCH_STBY"
SEC"1"
SEC_TYPE"0805"
CDS_LOCATION"C3L8"
CDS_LIB"mstr_discrete";
"A"
$PN"1"30;
"B"
$PN"2"18;
%"GND"
"1","(6000,4150)","0","mstr_symbols","I27";
;
HDL_POWER"GND"
BODY_TYPE"PLUMBING"
BOM_COST"PROC_VRD_PVCCIO_CPU0"
ROOM"PVCCIO_CPU0"
CDS_LIB"mstr_symbols"
SIZE"1B"
VOLTAGE"0.0V";
"A\NAC"18;
%"GND"
"1","(6025,2300)","0","mstr_symbols","I28";
;
SIZE"1B"
CDS_LIB"mstr_symbols"
VOLTAGE"0.0V"
BOM_COST"PROC_VRD_PVCCIO_CPU0"
ROOM"PVCCIO_CPU0"
BODY_TYPE"PLUMBING"
HDL_POWER"GND";
"A\NAC"19;
%"CAP"
"1","(6025,2875)","0","mstr_discrete","I29";
;
CDS_SEC"1"
PACK_TYPE"0805"
VOLTAGE"16V"
VALUE"10UF"
LOCATION"C3L9"
TOLERANCE"10%"
PART_NUMBER"C95333-007"
MATERIAL"X6S"
SEC_TYPE"0805"
SEC"1"
CDS_LOCATION"C3L9"
ROOM"P1V05_PCH_STBY_VR"
CDS_LIB"mstr_discrete";
"A"
$PN"1"31;
"B"
$PN"2"19;
%"CAP"
"1","(6250,2800)","0","mstr_discrete","I31";
;
CDS_SEC"1"
TOLERANCE"10%"
MATERIAL"X6S"
LOCATION"C3L7"
VALUE"10UF"
VOLTAGE"16V"
PACK_TYPE"0805"
PART_NUMBER"C95333-007"
ROOM"P1V05_PCH_STBY_VR"
SEC"1"
SEC_TYPE"0805"
CDS_LOCATION"C3L7"
CDS_LIB"mstr_discrete";
"A"
$PN"1"31;
"B"
$PN"2"19;
%"CAP"
"1","(6475,2875)","0","mstr_discrete","I32";
;
CDS_SEC"1"
MATERIAL"X6S"
VOLTAGE"16V"
VALUE"10UF"
PACK_TYPE"0805"
LOCATION"C3L10"
TOLERANCE"10%"
PART_NUMBER"C95333-007"
CDS_LIB"mstr_discrete"
ROOM"P1V05_PCH_STBY_VR"
CDS_LOCATION"C3L10"
SEC"1"
SEC_TYPE"0805";
"A"
$PN"1"31;
"B"
$PN"2"19;
%"CAP"
"1","(6700,2800)","0","mstr_discrete","I33";
;
CDS_SEC"1"
MATERIAL"X6S"
TOLERANCE"10%"
VOLTAGE"16V"
VALUE"1.0UF"
LOCATION"C7A9"
PACK_TYPE"0402"
PART_NUMBER"D97712-011"
SEC_TYPE"0402"
ROOM"P1V05_PCH_STBY_VR"
CDS_LOCATION"C7A9"
SEC"1"
CDS_LIB"mstr_discrete";
"A"
$PN"1"31;
"B"
$PN"2"19;
%"CAP"
"1","(7050,2100)","2","mstr_discrete","I34";
;
CDS_SEC"1"
CDS_LOCATION"C7A44"
PACK_TYPE"0402"
MATERIAL"X7R"
TOLERANCE"10%"
VOLTAGE"16V"
LOCATION"C7A44"
PART_NUMBER"A36096-104"
VALUE"0.220UF"
ROOM"P1V05_PCH_STBY_VR"
SEC"1"
CDS_LIB"mstr_discrete"
SPOF"TRUE"
SEC_TYPE"0402";
"A"
$PN"1"61;
"B"
$PN"2"33;
%"CAP_A"
"1","(6925,2875)","0","dev_discrete","I35";
;
CDS_LOCATION"C7A40"
MATERIAL"X7R"
TOLERANCE"10%"
VOLTAGE"16V"
VALUE"0.1UF"
LOCATION"C7A40"
PACK_TYPE"0402V"
PART_NUMBER"A36096-030"
CDS_LIB"dev_discrete"
CDS_SEC"1"
ROOM"P1V05_PCH_STBY_VR"
SEC_TYPE"0402V"
SEC"1";
"B"
$PN"2"19;
"A"
$PN"1"31;
%"CAP"
"1","(7175,2800)","0","mstr_discrete","I36";
;
CDS_SEC"1"
PACK_TYPE"0402"
VALUE"1.0UF"
VOLTAGE"16V"
TOLERANCE"10%"
MATERIAL"X6S"
PART_NUMBER"D97712-011"
LOCATION"C7A10"
ROOM"P1V05_PCH_STBY_VR"
SEC"1"
SEC_TYPE"0402"
CDS_LOCATION"C7A10"
CDS_LIB"mstr_discrete";
"A"
$PN"1"47;
"B"
$PN"2"19;
%"CAP"
"1","(8000,2875)","0","mstr_discrete","I39";
;
CDS_SEC"1"
CDS_LOCATION"C7A41"
LOCATION"C7A41"
PACK_TYPE"0402"
PART_NUMBER"A36096-155"
TOLERANCE"10%"
MATERIAL"X7R"
VOLTAGE"16V"
VALUE"0.22UF"
ROOM"P1V05_PCH_STBY_VR"
SEC"1"
SEC_TYPE"0402"
CDS_LIB"mstr_discrete";
"A"
$PN"1"20;
"B"
$PN"2"19;
%"P5V_STBY"
"1","(8525,3425)","0","mstr_symbols","I42";
;
CDS_LIB"mstr_symbols"
VOLTAGE"5.0V"
SIZE"1B"
BODY_TYPE"PLUMBING"
HDL_POWER"P5V_STBY";
"G\NAC"20;
%"GND"
"1","(10450,1875)","0","mstr_symbols","I44";
;
CDS_LIB"mstr_symbols"
SIZE"1B"
VOLTAGE"0.0V"
ROOM"PVCCIO_CPU0"
BOM_COST"PROC_VRD_PVCCIO_CPU0"
BODY_TYPE"PLUMBING"
HDL_POWER"GND";
"A\NAC"21;
%"CAP"
"1","(11650,2050)","0","mstr_discrete","I46";
;
CDS_SEC"1"
PART_NUMBER"C95333-002"
LOCATION"C7A42"
VALUE"22UF"
VOLTAGE"4V"
TOLERANCE"20%"
PACK_TYPE"0805LF"
MATERIAL"X6S"
CDS_LIB"mstr_discrete"
ROOM"P1V05_PCH_STBY_VR"
BOM_COST"PROC_VRD_PVCCIO_CPU0"
SEC_TYPE"0805LF"
SEC"1"
CDS_LOCATION"C7A42";
"A"
$PN"1"23;
"B"
$PN"2"22;
%"GND"
"1","(11650,1825)","0","mstr_symbols","I47";
;
ROOM"PVCCIO_CPU0"
BOM_COST"PROC_VRD_PVCCIO_CPU0"
VOLTAGE"0.0V"
CDS_LIB"mstr_symbols"
SIZE"1B"
BODY_TYPE"PLUMBING"
HDL_POWER"GND";
"A\NAC"22;
%"P1V05_PCH_STBY"
"1","(12700,2375)","0","mstr_symbols","I48";
;
VOLTAGE"1.05V"
CDS_LIB"mstr_symbols"
BOM_COST"PROC_VRD_PVCCIO_CPU0"
ROOM"PVCCIO_CPU0"
BODY_TYPE"PLUMBING"
HDL_POWER"P1V05_PCH_STBY";
"G\NAC"23;
%"P1V05_PCH_STBY"
"1","(7675,1500)","0","mstr_symbols","I55";
;
ROOM"PVCCIO_CPU0"
BOM_COST"PROC_VRD_PVCCIO_CPU0"
CDS_LIB"mstr_symbols"
VOLTAGE"1.05V"
BODY_TYPE"PLUMBING"
HDL_POWER"P1V05_PCH_STBY";
"G\NAC"24;
%"RES"
"1","(7450,1300)","0","mstr_discrete","I56";
;
CDS_SEC"1"
LOCATION"R8B14"
VALUE"0.0"
WATTAGE"1/16W"
TOLERANCE"5%"
PART_NUMBER"G21497-005"
MATERIAL"CHIP"
PACK_TYPE"0402"
BOM_COST"P1V05_PCH_STBY"
ROOM"P1V05_PCH_STBY"
CDS_LIB"mstr_discrete"
SEC"1"
SEC_TYPE"0402"
CDS_LOCATION"R8B14";
"B"
$PN"2"24;
"A"
$PN"1"62;
%"RES"
"2","(7175,1050)","0","mstr_discrete","I57";
;
CDS_SEC"1"
PACK_TYPE"0402"
LOCATION"R8B15"
VALUE"100.0"
MATERIAL"EMPTY"
TOLERANCE"1%"
WATTAGE"1/16W"
PART_NUMBER"G21796-017"
CDS_LIB"mstr_discrete"
CDS_LOCATION"R8B15"
SEC_TYPE"0402"
SEC"1"
NO_XNET_CONNECTION"1"
ROOM"P1V05_PCH_STBY"
BOM_COST"P1V05_PCH_STBY";
"A"
$PN"1"62;
"B"
$PN"2"63;
%"GND"
"1","(7650,625)","0","mstr_symbols","I58";
;
SIZE"1B"
VOLTAGE"0"
CDS_LIB"mstr_symbols"
BOM_COST"MEM_VRD_PVPP_AB"
ROOM"VCCP_CPU0_VR"
BODY_TYPE"PLUMBING"
HDL_POWER"GND";
"A\NAC"25;
%"RES"
"1","(7425,850)","0","mstr_discrete","I59";
;
CDS_SEC"1"
WATTAGE"1/16W"
PACK_TYPE"0402"
VALUE"0.0"
TOLERANCE"5%"
LOCATION"R8B12"
MATERIAL"CHIP"
PART_NUMBER"G21497-005"
SEC_TYPE"0402"
SEC"1"
BOM_COST"P1V05_PCH_STBY"
CDS_LIB"mstr_discrete"
CDS_LOCATION"R8B12"
ROOM"P1V05_PCH_STBY";
"B"
$PN"2"25;
"A"
$PN"1"63;
%"PVNN_PCH_STBY"
"1","(12650,4075)","0","mstr_symbols","I7";
;
HDL_POWER"PVNN_PCH_STBY"
BODY_TYPE"PLUMBING"
VOLTAGE"1.0V"
CDS_LIB"mstr_symbols"
BOM_COST"PROC_VRD_PVCCIO_CPU0"
ROOM"PVCCIO_CPU0";
"G\NAC"26;
%"CAPP"
"1","(12025,3775)","0","mstr_discrete","I71";
;
CDS_SEC"1"
VOLTAGE"2V"
TOLERANCE"20%"
PACK_TYPE"SM"
VALUE"470UF"
LOCATION"C3L18"
MATERIAL"ALUM"
PART_NUMBER"699013-031"
CDS_LIB"mstr_discrete"
SEC_TYPE"SM"
SEC"1"
CDS_LOCATION"C3L18"
ROOM"PVNN_PCH_STBY";
"B"
$PN"2"27;
"A"
$PN"1"26;
%"CAPP"
"1","(12325,3775)","0","mstr_discrete","I73";
;
CDS_SEC"1"
VOLTAGE"2V"
TOLERANCE"20%"
VALUE"470UF"
PACK_TYPE"SM"
LOCATION"C3L20"
MATERIAL"ALUM"
PART_NUMBER"699013-031"
CDS_LIB"mstr_discrete"
SEC_TYPE"SM"
SEC"1"
CDS_LOCATION"C3L20"
ROOM"PVNN_PCH_STBY";
"B"
$PN"2"27;
"A"
$PN"1"26;
%"CAPP"
"1","(12600,3775)","0","mstr_discrete","I74";
;
CDS_SEC"1"
LOCATION"C3L21"
VALUE"470UF"
TOLERANCE"20%"
VOLTAGE"2V"
MATERIAL"ALUM"
PACK_TYPE"SM"
PART_NUMBER"699013-031"
CDS_LIB"mstr_discrete"
SEC_TYPE"SM"
SEC"1"
CDS_LOCATION"C3L21"
ROOM"PVNN_PCH_STBY";
"B"
$PN"2"27;
"A"
$PN"1"26;
%"CAPP"
"1","(12850,3775)","0","mstr_discrete","I75";
;
CDS_SEC"1"
LOCATION"C7A27"
VALUE"470UF"
VOLTAGE"2V"
MATERIAL"ALUM"
PACK_TYPE"SM"
TOLERANCE"20%"
PART_NUMBER"699013-031"
CDS_LIB"mstr_discrete"
CDS_LOCATION"C7A27"
SEC_TYPE"SM"
SEC"1"
ROOM"PVNN_PCH_STBY";
"B"
$PN"2"27;
"A"
$PN"1"26;
%"CAPP"
"1","(11925,2050)","0","mstr_discrete","I76";
;
CDS_SEC"1"
VOLTAGE"2V"
LOCATION"C3L19"
VALUE"470UF"
TOLERANCE"20%"
MATERIAL"ALUM"
PACK_TYPE"SM"
PART_NUMBER"699013-031"
CDS_LIB"mstr_discrete"
CDS_LOCATION"C3L19"
ROOM"P1V05_PCH_STBY"
SEC_TYPE"SM"
SEC"1";
"B"
$PN"2"22;
"A"
$PN"1"23;
%"CAPP"
"1","(12175,2050)","0","mstr_discrete","I77";
;
CDS_SEC"1"
TOLERANCE"20%"
VALUE"470UF"
LOCATION"C2L46"
PART_NUMBER"699013-031"
VOLTAGE"2V"
PACK_TYPE"SM"
MATERIAL"ALUM"
ROOM"P1V05_PCH_STBY"
CDS_LOCATION"C2L46"
CDS_LIB"mstr_discrete"
SEC"1"
SEC_TYPE"SM";
"B"
$PN"2"22;
"A"
$PN"1"23;
%"CAPP"
"1","(12425,2050)","0","mstr_discrete","I78";
;
CDS_SEC"1"
VOLTAGE"2V"
PACK_TYPE"SM"
VALUE"470UF"
TOLERANCE"20%"
PART_NUMBER"699013-031"
LOCATION"C8A15"
MATERIAL"ALUM"
CDS_LIB"mstr_discrete"
CDS_LOCATION"C8A15"
ROOM"P1V05_PCH_STBY"
SEC"1"
SEC_TYPE"SM";
"B"
$PN"2"22;
"A"
$PN"1"23;
%"CAPP"
"1","(12700,2050)","0","mstr_discrete","I79";
;
CDS_SEC"1"
LOCATION"C2L25"
VALUE"470UF"
TOLERANCE"20%"
PACK_TYPE"SM"
PART_NUMBER"699013-031"
VOLTAGE"2V"
MATERIAL"ALUM"
CDS_LIB"mstr_discrete"
CDS_LOCATION"C2L25"
ROOM"P1V05_PCH_STBY"
SEC"1"
SEC_TYPE"SM";
"B"
$PN"2"22;
"A"
$PN"1"23;
%"GND"
"1","(11725,3550)","0","mstr_symbols","I8";
;
BOM_COST"PROC_VRD_PVCCIO_CPU0"
ROOM"PVCCIO_CPU0"
VOLTAGE"0.0V"
SIZE"1B"
CDS_LIB"mstr_symbols"
BODY_TYPE"PLUMBING"
HDL_POWER"GND";
"A\NAC"27;
%"GND"
"1","(9000,850)","0","mstr_symbols","I82";
;
SIZE"1B"
CDS_LIB"mstr_symbols"
VOLTAGE"0"
BOM_COST"MEM_VRD_PVPP_AB"
ROOM"VCCP_CPU0_VR"
BODY_TYPE"PLUMBING"
HDL_POWER"GND";
"A\NAC"28;
%"PVNN_PCH_STBY"
"1","(9550,1500)","0","mstr_symbols","I87";
;
ROOM"PVCCIO_CPU0"
CDS_LIB"mstr_symbols"
BOM_COST"PROC_VRD_PVCCIO_CPU0"
VOLTAGE"1.0V"
BODY_TYPE"PLUMBING"
HDL_POWER"PVNN_PCH_STBY";
"G\NAC"29;
%"CAP"
"1","(11725,3775)","0","mstr_discrete","I9";
;
CDS_SEC"1"
LOCATION"C7A30"
VALUE"22UF"
MATERIAL"X6S"
PACK_TYPE"0805LF"
VOLTAGE"4V"
TOLERANCE"20%"
PART_NUMBER"C95333-002"
CDS_LIB"mstr_discrete"
ROOM"PVNN_PCH_STBY"
CDS_LOCATION"C7A30"
SEC"1"
BOM_COST"PROC_VRD_PVCCIO_CPU0"
SEC_TYPE"0805LF";
"A"
$PN"1"26;
"B"
$PN"2"27;
%"RES"
"1","(9200,1400)","0","mstr_discrete","I90";
;
CDS_SEC"1"
LOCATION"R7A13"
MATERIAL"CHIP"
PART_NUMBER"G21796-017"
PACK_TYPE"0402"
TOLERANCE"1%"
VALUE"100.0"
WATTAGE"1/16W"
SEC_TYPE"0402"
SEC"1"
ROOM"P1V05_PCH_STBY"
BOM_COST"P1V05_PCH_STBY"
CDS_LOCATION"R7A13"
SPOF"TRUE"
CDS_LIB"mstr_discrete";
"B"
$PN"2"29;
"A"
$PN"1"49;
%"RES"
"1","(9200,950)","0","mstr_discrete","I92";
;
CDS_SEC"1"
PACK_TYPE"0402"
MATERIAL"CHIP"
WATTAGE"1/16W"
TOLERANCE"5%"
PART_NUMBER"G21497-005"
VALUE"0.0"
LOCATION"R7A18"
ROOM"P1V05_PCH_STBY"
SPOF"TRUE"
CDS_LOCATION"R7A18"
BOM_COST"P1V05_PCH_STBY"
CDS_LIB"mstr_discrete"
SEC"1"
SEC_TYPE"0402";
"B"
$PN"2"50;
"A"
$PN"1"28;
%"RES"
"1","(8725,1175)","0","mstr_discrete","I93";
;
CDS_SEC"1"
NO_XNET_CONNECTION"1"
VALUE"10.0"
PACK_TYPE"0402"
MATERIAL"CHIP"
WATTAGE"1/16W"
TOLERANCE"1%"
PART_NUMBER"G21796-066"
LOCATION"R7A19"
BOM_COST"P1V05_PCH_STBY"
CDS_LIB"mstr_discrete"
SPOF"TRUE"
SEC_TYPE"0402"
SEC"1"
CDS_LOCATION"R7A19"
ROOM"P1V05_PCH_STBY";
"B"
$PN"2"49;
"A"
$PN"1"51;
%"RES"
"1","(8750,900)","0","mstr_discrete","I94";
;
CDS_SEC"1"
PACK_TYPE"0402"
WATTAGE"1/16W"
TOLERANCE"1%"
VALUE"10.0"
MATERIAL"CHIP"
NO_XNET_CONNECTION"1"
PART_NUMBER"G21796-066"
LOCATION"R7A14"
BOM_COST"P1V05_PCH_STBY"
SPOF"TRUE"
SEC_TYPE"0402"
SEC"1"
ROOM"P1V05_PCH_STBY"
CDS_LOCATION"R7A14"
CDS_LIB"mstr_discrete";
"B"
$PN"2"49;
"A"
$PN"1"56;
%"VCC_CORE"
"1","(6275,4900)","0","mstr_symbols","I95";
;
HDL_POWER"VR_FET_SW_P12V_STBY_PVDDQ_DEF"
CDS_LIB"mstr_symbols";
"A"30;
%"VCC_CORE"
"1","(6250,3125)","0","mstr_symbols","I96";
;
HDL_POWER"VR_FET_SW_P12V_STBY_PVDDQ_DEF"
CDS_LIB"mstr_symbols";
"A"31;
%"VCC_CORE"
"1","(12700,1400)","0","mstr_symbols","I97";
;
HDL_POWER"VR_FET_SW_P12V_STBY_PVDDQ_DEF"
CDS_LIB"mstr_symbols";
"A"32;
END.
